# T6G (Grand Teton) — schematic netlist excerpt (pin names and nets, part order shuffled) for the footprints in the layout excerpt that follows; sources: Cadence DE-HDL packaged netlist, KiCad conversion of 04192023_DAF0TMB3IC0_F0TG_MB_C_brd_V02_OCP.brd

PR3795  Q_RES  25.5K 1% CHIP  pkg 0402LF  page 140 : A = P3V3_AUX ; B = P3V3_OCP_UV_2
R2918  Q_RES  4.7K 5% CHIP  pkg 0402LF  page 128 : A = FM_SWB_PWR_EN_R ; B = GND

(kicad_pcb
	(version 20260206)
	(generator "pcbnew")
	(generator_version "10.0")
	(general
		(thickness 1.6)
		(legacy_teardrops no)
	)
	(paper "A4")
	(title_block
		(title "04192023_DAF0TMB3IC0_F0TG_MB_C_brd_V02_OCP.brd")
		(comment 1 "Grand Teton / footprints 2816-2817 of 8354")
	)
	(layers
		(0 "F.Cu" signal "TOP")
		(4 "In1.Cu" signal "GND")
		(6 "In2.Cu" signal "IN1")
		(8 "In3.Cu" signal "GND1")
		(10 "In4.Cu" signal "IN2")
		(12 "In5.Cu" signal "GND2")
		(14 "In6.Cu" signal "IN3")
		(16 "In7.Cu" signal "GND3")
		(18 "In8.Cu" signal "VCC")
		(20 "In9.Cu" signal "VCC1")
		(22 "In10.Cu" signal "GND4")
		(24 "In11.Cu" signal "IN4")
		(26 "In12.Cu" signal "GND5")
		(28 "In13.Cu" signal "IN5")
		(30 "In14.Cu" signal "GND6")
		(32 "In15.Cu" signal "IN6")
		(34 "In16.Cu" signal "GND7")
		(2 "B.Cu" signal "BOTTOM")
		(9 "F.Adhes" user "F.Adhesive")
		(11 "B.Adhes" user "B.Adhesive")
		(13 "F.Paste" user "Package Geometry/Pastemask Top")
		(15 "B.Paste" user "Package Geometry/Pastemask Bottom")
		(5 "F.SilkS" user "Ref Des/Silkscreen Top")
		(7 "B.SilkS" user "Ref Des/Silkscreen Bottom")
		(1 "F.Mask" user "Board Geometry/Soldermask Top")
		(3 "B.Mask" user "Board Geometry/Soldermask Bottom")
		(17 "Dwgs.User" user "User.Drawings")
		(19 "Cmts.User" user "User.Comments")
		(21 "Eco1.User" user "User.Eco1")
		(23 "Eco2.User" user "User.Eco2")
		(25 "Edge.Cuts" user "Board Geometry/Outline")
		(27 "Margin" user)
		(31 "F.CrtYd" user "Package Geometry/Place Bound Top")
		(29 "B.CrtYd" user "Package Geometry/Place Bound Bottom")
		(35 "F.Fab" user "Ref Des/Assembly Top")
		(33 "B.Fab" user "Ref Des/Assembly Bottom")
	)
	(footprint ""
		(layer "F.Cu")
		(at 95.39097 -60.86221 180)
		(property "Reference" "PR3795"
			(at 0 0 180)
			(layer "F.SilkS")
			(hide yes)
			(effects
				(font
					(size 1.27 1.27)
				)
			)
		)
		(property "Value" ""
			(at 0 0 180)
			(layer "F.Fab")
			(effects
				(font
					(size 1.27 1.27)
				)
			)
		)
		(duplicate_pad_numbers_are_jumpers no)
		(fp_line
			(start 0.7874 0.4064)
			(end -0.7874 0.4064)
			(stroke
				(width 0.1524)
				(type default)
			)
			(layer "F.SilkS")
		)
		(fp_line
			(start 0.7874 -0.4064)
			(end 0.7874 0.4064)
			(stroke
				(width 0.1524)
				(type default)
			)
			(layer "F.SilkS")
		)
		(fp_line
			(start -0.7874 0.4064)
			(end -0.7874 -0.4064)
			(stroke
				(width 0.1524)
				(type default)
			)
			(layer "F.SilkS")
		)
		(fp_line
			(start -0.7874 -0.4064)
			(end 0.7874 -0.4064)
			(stroke
				(width 0.1524)
				(type default)
			)
			(layer "F.SilkS")
		)
		(fp_line
			(start 0.67945 0.3048)
			(end 0.120396 0.3048)
			(stroke
				(width 0.1)
				(type default)
			)
			(layer "F.Fab")
		)
		(fp_line
			(start 0.67945 -0.3048)
			(end 0.67945 0.3048)
			(stroke
				(width 0.1)
				(type default)
			)
			(layer "F.Fab")
		)
		(fp_line
			(start 0.12065 -0.2794)
			(end 0.12065 -0.3048)
			(stroke
				(width 0.1)
				(type default)
			)
			(layer "F.Fab")
		)
		(fp_line
			(start 0.12065 -0.3048)
			(end 0.67945 -0.3048)
			(stroke
				(width 0.1)
				(type default)
			)
			(layer "F.Fab")
		)
		(fp_line
			(start 0.120396 0.3048)
			(end 0.120396 0.2794)
			(stroke
				(width 0.1)
				(type default)
			)
			(layer "F.Fab")
		)
		(fp_line
			(start 0.120396 0.2794)
			(end -0.12065 0.2794)
			(stroke
				(width 0.1)
				(type default)
			)
			(layer "F.Fab")
		)
		(fp_line
			(start -0.12065 0.3048)
			(end -0.67945 0.3048)
			(stroke
				(width 0.1)
				(type default)
			)
			(layer "F.Fab")
		)
		(fp_line
			(start -0.12065 0.2794)
			(end -0.12065 0.3048)
			(stroke
				(width 0.1)
				(type default)
			)
			(layer "F.Fab")
		)
		(fp_line
			(start -0.12065 -0.2794)
			(end 0.12065 -0.2794)
			(stroke
				(width 0.1)
				(type default)
			)
			(layer "F.Fab")
		)
		(fp_line
			(start -0.12065 -0.305054)
			(end -0.12065 -0.2794)
			(stroke
				(width 0.1)
				(type default)
			)
			(layer "F.Fab")
		)
		(fp_line
			(start -0.67945 0.3048)
			(end -0.67945 -0.305054)
			(stroke
				(width 0.1)
				(type default)
			)
			(layer "F.Fab")
		)
		(fp_line
			(start -0.67945 -0.305054)
			(end -0.12065 -0.305054)
			(stroke
				(width 0.1)
				(type default)
			)
			(layer "F.Fab")
		)
		(pad "1" smd circle
			(at -0.40005 0 180)
			(size 0 0)
			(layers "F.Cu" "F.Mask" "F.Paste")
			(net "P3V3_AUX")
		)
		(pad "2" smd circle
			(at 0.40005 0 180)
			(size 0 0)
			(layers "F.Cu" "F.Mask" "F.Paste")
			(net "P3V3_OCP_UV_2")
		)
	)
	(footprint ""
		(layer "F.Cu")
		(at 38.0746 -435.448964 -90)
		(property "Reference" "R2918"
			(at 0 0 270)
			(layer "F.SilkS")
			(hide yes)
			(effects
				(font
					(size 1.27 1.27)
				)
			)
		)
		(property "Value" ""
			(at 0 0 270)
			(layer "F.Fab")
			(effects
				(font
					(size 1.27 1.27)
				)
			)
		)
		(duplicate_pad_numbers_are_jumpers no)
		(fp_line
			(start -0.7874 0.4064)
			(end -0.7874 -0.4064)
			(stroke
				(width 0.1524)
				(type default)
			)
			(layer "F.SilkS")
		)
		(fp_line
			(start 0.7874 0.4064)
			(end -0.7874 0.4064)
			(stroke
				(width 0.1524)
				(type default)
			)
			(layer "F.SilkS")
		)
		(fp_line
			(start -0.7874 -0.4064)
			(end 0.7874 -0.4064)
			(stroke
				(width 0.1524)
				(type default)
			)
			(layer "F.SilkS")
		)
		(fp_line
			(start 0.7874 -0.4064)
			(end 0.7874 0.4064)
			(stroke
				(width 0.1524)
				(type default)
			)
			(layer "F.SilkS")
		)
		(fp_line
			(start -0.67945 0.3048)
			(end -0.67945 -0.305054)
			(stroke
				(width 0.1)
				(type default)
			)
			(layer "F.Fab")
		)
		(fp_line
			(start -0.12065 0.3048)
			(end -0.67945 0.3048)
			(stroke
				(width 0.1)
				(type default)
			)
			(layer "F.Fab")
		)
		(fp_line
			(start 0.120396 0.3048)
			(end 0.120396 0.2794)
			(stroke
				(width 0.1)
				(type default)
			)
			(layer "F.Fab")
		)
		(fp_line
			(start 0.67945 0.3048)
			(end 0.120396 0.3048)
			(stroke
				(width 0.1)
				(type default)
			)
			(layer "F.Fab")
		)
		(fp_line
			(start -0.12065 0.2794)
			(end -0.12065 0.3048)
			(stroke
				(width 0.1)
				(type default)
			)
			(layer "F.Fab")
		)
		(fp_line
			(start 0.120396 0.2794)
			(end -0.12065 0.2794)
			(stroke
				(width 0.1)
				(type default)
			)
			(layer "F.Fab")
		)
		(fp_line
			(start -0.12065 -0.2794)
			(end 0.12065 -0.2794)
			(stroke
				(width 0.1)
				(type default)
			)
			(layer "F.Fab")
		)
		(fp_line
			(start 0.12065 -0.2794)
			(end 0.12065 -0.3048)
			(stroke
				(width 0.1)
				(type default)
			)
			(layer "F.Fab")
		)
		(fp_line
			(start 0.12065 -0.3048)
			(end 0.67945 -0.3048)
			(stroke
				(width 0.1)
				(type default)
			)
			(layer "F.Fab")
		)
		(fp_line
			(start 0.67945 -0.3048)
			(end 0.67945 0.3048)
			(stroke
				(width 0.1)
				(type default)
			)
			(layer "F.Fab")
		)
		(fp_line
			(start -0.67945 -0.305054)
			(end -0.12065 -0.305054)
			(stroke
				(width 0.1)
				(type default)
			)
			(layer "F.Fab")
		)
		(fp_line
			(start -0.12065 -0.305054)
			(end -0.12065 -0.2794)
			(stroke
				(width 0.1)
				(type default)
			)
			(layer "F.Fab")
		)
		(pad "1" smd circle
			(at -0.40005 0 270)
			(size 0 0)
			(layers "F.Cu" "F.Mask" "F.Paste")
			(net "FM_SWB_PWR_EN_R")
		)
		(pad "2" smd circle
			(at 0.40005 0 270)
			(size 0 0)
			(layers "F.Cu" "F.Mask" "F.Paste")
			(net "GND")
		)
	)
)
